# S9S_MB_2U (Grand Teton) — schematic netlist excerpt (pin names and nets, part order shuffled) for the footprints in the layout excerpt that follows; sources: Cadence DE-HDL packaged netlist, KiCad conversion of 03242023_DA0F0TMBIJ0_F0T_Motherboard_J_brd_V01_OCP.brd

C368  Q_CAP  47UF 4V 20% X6S  pkg C0805  page 75 : A = PVCCIN_CPU0 ; B = GND
R51  Q_RES  100 1% CHIP  pkg 0402LF  page 47 : A = DBP_CPU1_MBP0_GTL_R_N ; B = DBP_CPU_MBP0_GTL_N
R11  Q_RES  33.2 1% CHIP  pkg 0402LF  page 14 : A = H_CPU0_PMDOWN_CPU1_R1 ; B = H_CPU0_PMDOWN_CPU1

(kicad_pcb
	(version 20260206)
	(generator "pcbnew")
	(generator_version "10.0")
	(general
		(thickness 1.6)
		(legacy_teardrops no)
	)
	(paper "A4")
	(title_block
		(title "03242023_DA0F0TMBIJ0_F0T_Motherboard_J_brd_V01_OCP.brd")
		(comment 1 "Grand Teton / footprints 4996-4998 of 6105")
	)
	(layers
		(0 "F.Cu" signal "TOP")
		(4 "In1.Cu" signal "GND")
		(6 "In2.Cu" signal "IN1")
		(8 "In3.Cu" signal "GND1")
		(10 "In4.Cu" signal "IN2")
		(12 "In5.Cu" signal "GND2")
		(14 "In6.Cu" signal "IN3")
		(16 "In7.Cu" signal "GND3")
		(18 "In8.Cu" signal "VCC")
		(20 "In9.Cu" signal "VCC1")
		(22 "In10.Cu" signal "GND4")
		(24 "In11.Cu" signal "IN4")
		(26 "In12.Cu" signal "GND5")
		(28 "In13.Cu" signal "IN5")
		(30 "In14.Cu" signal "GND6")
		(32 "In15.Cu" signal "IN6")
		(34 "In16.Cu" signal "GND7")
		(2 "B.Cu" signal "BOTTOM")
		(9 "F.Adhes" user "F.Adhesive")
		(11 "B.Adhes" user "B.Adhesive")
		(13 "F.Paste" user "Package Geometry/Pastemask Top")
		(15 "B.Paste" user "Package Geometry/Pastemask Bottom")
		(5 "F.SilkS" user "Ref Des/Silkscreen Top")
		(7 "B.SilkS" user "Ref Des/Silkscreen Bottom")
		(1 "F.Mask" user "Board Geometry/Soldermask Top")
		(3 "B.Mask" user "Board Geometry/Soldermask Bottom")
		(17 "Dwgs.User" user "User.Drawings")
		(19 "Cmts.User" user "User.Comments")
		(21 "Eco1.User" user "User.Eco1")
		(23 "Eco2.User" user "User.Eco2")
		(25 "Edge.Cuts" user "Board Geometry/Outline")
		(27 "Margin" user)
		(31 "F.CrtYd" user "Package Geometry/Place Bound Top")
		(29 "B.CrtYd" user "Package Geometry/Place Bound Bottom")
		(35 "F.Fab" user "Ref Des/Assembly Top")
		(33 "B.Fab" user "Ref Des/Assembly Bottom")
	)
	(footprint ""
		(layer "B.Cu")
		(at 80.763618 -190.83401 90)
		(property "Reference" "R51"
			(at 0 0 90)
			(layer "B.SilkS")
			(hide yes)
			(effects
				(font
					(size 1.27 1.27)
				)
				(justify mirror)
			)
		)
		(property "Value" ""
			(at 0 0 90)
			(layer "B.Fab")
			(effects
				(font
					(size 1.27 1.27)
				)
				(justify mirror)
			)
		)
		(duplicate_pad_numbers_are_jumpers no)
		(fp_line
			(start 0.7874 -0.4064)
			(end -0.7874 -0.4064)
			(stroke
				(width 0.1524)
				(type default)
			)
			(layer "B.SilkS")
		)
		(fp_line
			(start -0.7874 -0.4064)
			(end -0.7874 0.4064)
			(stroke
				(width 0.1524)
				(type default)
			)
			(layer "B.SilkS")
		)
		(fp_line
			(start 0.7874 0.4064)
			(end 0.7874 -0.4064)
			(stroke
				(width 0.1524)
				(type default)
			)
			(layer "B.SilkS")
		)
		(fp_line
			(start -0.7874 0.4064)
			(end 0.7874 0.4064)
			(stroke
				(width 0.1524)
				(type default)
			)
			(layer "B.SilkS")
		)
		(fp_line
			(start 0.67945 -0.305054)
			(end 0.12065 -0.305054)
			(stroke
				(width 0.1)
				(type default)
			)
			(layer "B.Fab")
		)
		(fp_line
			(start 0.12065 -0.305054)
			(end 0.12065 -0.2794)
			(stroke
				(width 0.1)
				(type default)
			)
			(layer "B.Fab")
		)
		(fp_line
			(start -0.12065 -0.3048)
			(end -0.67945 -0.3048)
			(stroke
				(width 0.1)
				(type default)
			)
			(layer "B.Fab")
		)
		(fp_line
			(start -0.67945 -0.3048)
			(end -0.67945 0.3048)
			(stroke
				(width 0.1)
				(type default)
			)
			(layer "B.Fab")
		)
		(fp_line
			(start 0.12065 -0.2794)
			(end -0.12065 -0.2794)
			(stroke
				(width 0.1)
				(type default)
			)
			(layer "B.Fab")
		)
		(fp_line
			(start -0.12065 -0.2794)
			(end -0.12065 -0.3048)
			(stroke
				(width 0.1)
				(type default)
			)
			(layer "B.Fab")
		)
		(fp_line
			(start 0.12065 0.2794)
			(end 0.12065 0.3048)
			(stroke
				(width 0.1)
				(type default)
			)
			(layer "B.Fab")
		)
		(fp_line
			(start -0.120396 0.2794)
			(end 0.12065 0.2794)
			(stroke
				(width 0.1)
				(type default)
			)
			(layer "B.Fab")
		)
		(fp_line
			(start 0.67945 0.3048)
			(end 0.67945 -0.305054)
			(stroke
				(width 0.1)
				(type default)
			)
			(layer "B.Fab")
		)
		(fp_line
			(start 0.12065 0.3048)
			(end 0.67945 0.3048)
			(stroke
				(width 0.1)
				(type default)
			)
			(layer "B.Fab")
		)
		(fp_line
			(start -0.120396 0.3048)
			(end -0.120396 0.2794)
			(stroke
				(width 0.1)
				(type default)
			)
			(layer "B.Fab")
		)
		(fp_line
			(start -0.67945 0.3048)
			(end -0.120396 0.3048)
			(stroke
				(width 0.1)
				(type default)
			)
			(layer "B.Fab")
		)
		(pad "1" smd circle
			(at 0.40005 0 270)
			(size 0 0)
			(layers "B.Cu" "B.Mask" "B.Paste")
			(net "DBP_CPU1_MBP0_GTL_R_N")
		)
		(pad "2" smd circle
			(at -0.40005 0 270)
			(size 0 0)
			(layers "B.Cu" "B.Mask" "B.Paste")
			(net "DBP_CPU_MBP0_GTL_N")
		)
	)
	(footprint ""
		(layer "B.Cu")
		(at 353.619308 -252.176026 -90)
		(property "Reference" "C368"
			(at 0 0 90)
			(layer "B.SilkS")
			(hide yes)
			(effects
				(font
					(size 1.27 1.27)
				)
				(justify mirror)
			)
		)
		(property "Value" ""
			(at 0 0 90)
			(layer "B.Fab")
			(effects
				(font
					(size 1.27 1.27)
				)
				(justify mirror)
			)
		)
		(duplicate_pad_numbers_are_jumpers no)
		(fp_line
			(start -1.524 0.762)
			(end 1.524 0.762)
			(stroke
				(width 0.1524)
				(type default)
			)
			(layer "B.SilkS")
		)
		(fp_line
			(start 1.524 0.762)
			(end 1.524 -0.762)
			(stroke
				(width 0.1524)
				(type default)
			)
			(layer "B.SilkS")
		)
		(fp_line
			(start -1.524 -0.762)
			(end -1.524 0.762)
			(stroke
				(width 0.1524)
				(type default)
			)
			(layer "B.SilkS")
		)
		(fp_line
			(start 1.524 -0.762)
			(end -1.524 -0.762)
			(stroke
				(width 0.1524)
				(type default)
			)
			(layer "B.SilkS")
		)
		(fp_line
			(start -1.1049 0.724916)
			(end -1.1049 -0.724916)
			(stroke
				(width 0.1)
				(type default)
			)
			(layer "B.Fab")
		)
		(fp_line
			(start 1.1049 0.724916)
			(end -1.1049 0.724916)
			(stroke
				(width 0.1)
				(type default)
			)
			(layer "B.Fab")
		)
		(fp_line
			(start -1.1049 -0.724916)
			(end 1.1049 -0.724916)
			(stroke
				(width 0.1)
				(type default)
			)
			(layer "B.Fab")
		)
		(fp_line
			(start 1.1049 -0.724916)
			(end 1.1049 0.724916)
			(stroke
				(width 0.1)
				(type default)
			)
			(layer "B.Fab")
		)
		(pad "1" smd rect
			(at 0.889 0 270)
			(size 1.016 1.27)
			(layers "B.Cu" "B.Mask" "B.Paste")
			(net "PVCCIN_CPU0")
		)
		(pad "2" smd rect
			(at -0.889 0 270)
			(size 1.016 1.27)
			(layers "B.Cu" "B.Mask" "B.Paste")
			(net "GND")
		)
	)
	(footprint ""
		(layer "B.Cu")
		(at 154.26436 -224.814638 -90)
		(property "Reference" "R11"
			(at 0 0 90)
			(layer "B.SilkS")
			(hide yes)
			(effects
				(font
					(size 1.27 1.27)
				)
				(justify mirror)
			)
		)
		(property "Value" ""
			(at 0 0 90)
			(layer "B.Fab")
			(effects
				(font
					(size 1.27 1.27)
				)
				(justify mirror)
			)
		)
		(duplicate_pad_numbers_are_jumpers no)
		(fp_line
			(start -0.7874 0.4064)
			(end 0.7874 0.4064)
			(stroke
				(width 0.1524)
				(type default)
			)
			(layer "B.SilkS")
		)
		(fp_line
			(start 0.7874 0.4064)
			(end 0.7874 -0.4064)
			(stroke
				(width 0.1524)
				(type default)
			)
			(layer "B.SilkS")
		)
		(fp_line
			(start -0.7874 -0.4064)
			(end -0.7874 0.4064)
			(stroke
				(width 0.1524)
				(type default)
			)
			(layer "B.SilkS")
		)
		(fp_line
			(start 0.7874 -0.4064)
			(end -0.7874 -0.4064)
			(stroke
				(width 0.1524)
				(type default)
			)
			(layer "B.SilkS")
		)
		(fp_line
			(start -0.67945 0.3048)
			(end -0.120396 0.3048)
			(stroke
				(width 0.1)
				(type default)
			)
			(layer "B.Fab")
		)
		(fp_line
			(start -0.120396 0.3048)
			(end -0.120396 0.2794)
			(stroke
				(width 0.1)
				(type default)
			)
			(layer "B.Fab")
		)
		(fp_line
			(start 0.12065 0.3048)
			(end 0.67945 0.3048)
			(stroke
				(width 0.1)
				(type default)
			)
			(layer "B.Fab")
		)
		(fp_line
			(start 0.67945 0.3048)
			(end 0.67945 -0.305054)
			(stroke
				(width 0.1)
				(type default)
			)
			(layer "B.Fab")
		)
		(fp_line
			(start -0.120396 0.2794)
			(end 0.12065 0.2794)
			(stroke
				(width 0.1)
				(type default)
			)
			(layer "B.Fab")
		)
		(fp_line
			(start 0.12065 0.2794)
			(end 0.12065 0.3048)
			(stroke
				(width 0.1)
				(type default)
			)
			(layer "B.Fab")
		)
		(fp_line
			(start -0.12065 -0.2794)
			(end -0.12065 -0.3048)
			(stroke
				(width 0.1)
				(type default)
			)
			(layer "B.Fab")
		)
		(fp_line
			(start 0.12065 -0.2794)
			(end -0.12065 -0.2794)
			(stroke
				(width 0.1)
				(type default)
			)
			(layer "B.Fab")
		)
		(fp_line
			(start -0.67945 -0.3048)
			(end -0.67945 0.3048)
			(stroke
				(width 0.1)
				(type default)
			)
			(layer "B.Fab")
		)
		(fp_line
			(start -0.12065 -0.3048)
			(end -0.67945 -0.3048)
			(stroke
				(width 0.1)
				(type default)
			)
			(layer "B.Fab")
		)
		(fp_line
			(start 0.12065 -0.305054)
			(end 0.12065 -0.2794)
			(stroke
				(width 0.1)
				(type default)
			)
			(layer "B.Fab")
		)
		(fp_line
			(start 0.67945 -0.305054)
			(end 0.12065 -0.305054)
			(stroke
				(width 0.1)
				(type default)
			)
			(layer "B.Fab")
		)
		(pad "1" smd circle
			(at 0.40005 0 90)
			(size 0 0)
			(layers "B.Cu" "B.Mask" "B.Paste")
			(net "H_CPU0_PMDOWN_CPU1_R1")
		)
		(pad "2" smd circle
			(at -0.40005 0 90)
			(size 0 0)
			(layers "B.Cu" "B.Mask" "B.Paste")
			(net "H_CPU0_PMDOWN_CPU1")
		)
	)
)
